(kicad_pcb
	(version 20241229)
	(generator "pcbnew")
	(generator_version "9.0")
	(general
		(thickness 1.62)
		(legacy_teardrops no)
	)
	(paper "A4")
	(title_block
		(title "OCuLink to 10GbE adapter")
		(date "2026-02-23")
		(rev "1.1.0")
		(company "Antmicro Ltd")
		(comment 1 "www.antmicro.com")
		(comment 9 "footprints 440-445 of 510")
	)
	(layers
		(0 "F.Cu" signal)
		(4 "In1.Cu" signal)
		(6 "In2.Cu" signal)
		(8 "In3.Cu" signal)
		(10 "In4.Cu" signal)
		(12 "In5.Cu" signal)
		(14 "In6.Cu" signal)
		(2 "B.Cu" signal)
		(9 "F.Adhes" user "F.Adhesive")
		(11 "B.Adhes" user "B.Adhesive")
		(13 "F.Paste" user)
		(15 "B.Paste" user)
		(5 "F.SilkS" user "F.Silkscreen")
		(7 "B.SilkS" user "B.Silkscreen")
		(1 "F.Mask" user)
		(3 "B.Mask" user)
		(17 "Dwgs.User" user "User.Drawings")
		(19 "Cmts.User" user "User.Comments")
		(21 "Eco1.User" user "User.Eco1")
		(23 "Eco2.User" user "User.Eco2")
		(25 "Edge.Cuts" user)
		(27 "Margin" user)
		(31 "F.CrtYd" user "F.Courtyard")
		(29 "B.CrtYd" user "B.Courtyard")
		(35 "F.Fab" user)
		(33 "B.Fab" user)
	)
	(footprint "antmicro-footprints:R_0402_1005Metric"
		(layer "B.Cu")
		(at 96.88 111.960001 180)
		(descr "Resistor SMD 0402")
		(tags "resistor SMD 0402")
		(property "Reference" "R49"
			(at 0.84 -0.509999 0)
			(layer "B.SilkS")
			(effects
				(font
					(size 0.7 0.7)
					(thickness 0.15)
				)
				(justify left bottom mirror)
			)
		)
		(property "Value" "R_100R_0402"
			(at -1.011843 -1.772046 0)
			(layer "B.Fab")
			(hide yes)
			(effects
				(font
					(size 0.7 0.7)
					(thickness 0.15)
				)
				(justify left bottom mirror)
			)
		)
		(property "Datasheet" "https://www.bourns.com/docs/product-datasheets/cr.pdf"
			(at 0 0 0)
			(layer "B.Fab")
			(hide yes)
			(effects
				(font
					(size 1.27 1.27)
					(thickness 0.15)
				)
				(justify mirror)
			)
		)
		(property "Description" "SMD Chip Resistor, 100 ohm, ± 1%, 62.5 mW, 0402 [1005 Metric], Thick Film, General Purpose"
			(at 0 0 0)
			(layer "B.Fab")
			(hide yes)
			(effects
				(font
					(size 1.27 1.27)
					(thickness 0.15)
				)
				(justify mirror)
			)
		)
		(property "MPN" "CR0402-FX-1000GLF"
			(at 0 0 180)
			(unlocked yes)
			(layer "B.Fab")
			(hide yes)
			(effects
				(font
					(size 1 1)
					(thickness 0.15)
				)
				(justify mirror)
			)
		)
		(property "Manufacturer" "Bourns"
			(at 0 0 180)
			(unlocked yes)
			(layer "B.Fab")
			(hide yes)
			(effects
				(font
					(size 1 1)
					(thickness 0.15)
				)
				(justify mirror)
			)
		)
		(property "License" "Apache-2.0"
			(at 0 0 180)
			(unlocked yes)
			(layer "B.Fab")
			(hide yes)
			(effects
				(font
					(size 1 1)
					(thickness 0.15)
				)
				(justify mirror)
			)
		)
		(property "Author" "Antmicro"
			(at 0 0 180)
			(unlocked yes)
			(layer "B.Fab")
			(hide yes)
			(effects
				(font
					(size 1 1)
					(thickness 0.15)
				)
				(justify mirror)
			)
		)
		(property "Val" "100R"
			(at 0 0 180)
			(unlocked yes)
			(layer "B.Fab")
			(hide yes)
			(effects
				(font
					(size 1 1)
					(thickness 0.15)
				)
				(justify mirror)
			)
		)
		(property "Tolerance" "1%"
			(at 0 0 180)
			(unlocked yes)
			(layer "B.Fab")
			(hide yes)
			(effects
				(font
					(size 1 1)
					(thickness 0.15)
				)
				(justify mirror)
			)
		)
		(sheetname "/X710-AT2 Misc/")
		(sheetfile "x710-at2-mics.kicad_sch")
		(attr smd)
		(fp_rect
			(start -0.925 0.47)
			(end 0.925 -0.47)
			(stroke
				(width 0.05)
				(type default)
			)
			(fill no)
			(layer "B.CrtYd")
		)
		(fp_rect
			(start -0.5 0.25)
			(end 0.5 -0.25)
			(stroke
				(width 0.15)
				(type solid)
			)
			(fill no)
			(layer "B.Fab")
		)
		(pad "1" smd roundrect
			(at -0.48 0 180)
			(size 0.59 0.64)
			(layers "B.Cu" "B.Mask" "B.Paste")
			(roundrect_rratio 0.25)
			(net 157 "Net-(U7-A_{2})")
			(pintype "passive")
		)
		(pad "2" smd roundrect
			(at 0.48 0 180)
			(size 0.59 0.64)
			(layers "B.Cu" "B.Mask" "B.Paste")
			(roundrect_rratio 0.25)
			(net 28 "GND")
			(pintype "passive")
		)
	)
	(footprint "antmicro-footprints:TP_SMD_1mm"
		(layer "B.Cu")
		(at 80.24 74.55 -90)
		(property "Reference" "TP33"
			(at -1.07 7.15 90)
			(layer "B.SilkS")
			(effects
				(font
					(size 0.7 0.7)
					(thickness 0.15)
				)
				(justify left bottom mirror)
			)
		)
		(property "Value" "TP_1mm_SMD"
			(at 0 -1.4 90)
			(layer "B.Fab")
			(hide yes)
			(effects
				(font
					(size 0.7 0.7)
					(thickness 0.15)
				)
				(justify left bottom mirror)
			)
		)
		(property "Description" "Test point 1mm SMD"
			(at 0 0 90)
			(layer "B.Fab")
			(hide yes)
			(effects
				(font
					(size 1.27 1.27)
					(thickness 0.15)
				)
				(justify mirror)
			)
		)
		(property "MPN" ""
			(at 0 0 90)
			(unlocked yes)
			(layer "B.Fab")
			(hide yes)
			(effects
				(font
					(size 1 1)
					(thickness 0.15)
				)
				(justify mirror)
			)
		)
		(property "Manufacturer" ""
			(at 0 0 90)
			(unlocked yes)
			(layer "B.Fab")
			(hide yes)
			(effects
				(font
					(size 1 1)
					(thickness 0.15)
				)
				(justify mirror)
			)
		)
		(property "Author" "Antmicro"
			(at 0 0 90)
			(unlocked yes)
			(layer "B.Fab")
			(hide yes)
			(effects
				(font
					(size 1 1)
					(thickness 0.15)
				)
				(justify mirror)
			)
		)
		(property "License" "Apache-2.0"
			(at 0 0 90)
			(unlocked yes)
			(layer "B.Fab")
			(hide yes)
			(effects
				(font
					(size 1 1)
					(thickness 0.15)
				)
				(justify mirror)
			)
		)
		(sheetname "/Power/")
		(sheetfile "power.kicad_sch")
		(attr exclude_from_pos_files exclude_from_bom)
		(fp_circle
			(center 0 0)
			(end 0.6 0)
			(stroke
				(width 0.05)
				(type default)
			)
			(fill no)
			(layer "B.CrtYd")
		)
		(pad "1" smd circle
			(at 0 0 270)
			(size 1 1)
			(layers "B.Cu" "B.Mask")
			(net 302 "+1V0")
			(pinfunction "1")
			(pintype "passive")
		)
	)
	(footprint "antmicro-footprints:TP_SMD_0.75mm"
		(layer "B.Cu")
		(at 87.725 104.85 90)
		(property "Reference" "TP13"
			(at 1.37 -2.115 180)
			(layer "B.SilkS")
			(effects
				(font
					(size 0.7 0.7)
					(thickness 0.15)
				)
				(justify right top mirror)
			)
		)
		(property "Value" "TP_0.75mm_SMD"
			(at 0 -1.2 90)
			(layer "B.Fab")
			(hide yes)
			(effects
				(font
					(size 0.7 0.7)
					(thickness 0.15)
				)
				(justify right top mirror)
			)
		)
		(property "Description" "SMT test point"
			(at 0 0 90)
			(layer "B.Fab")
			(hide yes)
			(effects
				(font
					(size 1.27 1.27)
					(thickness 0.15)
				)
				(justify mirror)
			)
		)
		(property "MPN" ""
			(at 0 0 90)
			(unlocked yes)
			(layer "B.Fab")
			(hide yes)
			(effects
				(font
					(size 1 1)
					(thickness 0.15)
				)
				(justify mirror)
			)
		)
		(property "Manufacturer" ""
			(at 0 0 90)
			(unlocked yes)
			(layer "B.Fab")
			(hide yes)
			(effects
				(font
					(size 1 1)
					(thickness 0.15)
				)
				(justify mirror)
			)
		)
		(property "Author" "Antmicro"
			(at 0 0 90)
			(unlocked yes)
			(layer "B.Fab")
			(hide yes)
			(effects
				(font
					(size 1 1)
					(thickness 0.15)
				)
				(justify mirror)
			)
		)
		(property "License" "Apache-2.0"
			(at 0 0 90)
			(unlocked yes)
			(layer "B.Fab")
			(hide yes)
			(effects
				(font
					(size 1 1)
					(thickness 0.15)
				)
				(justify mirror)
			)
		)
		(sheetname "/X710-AT2 Misc/")
		(sheetfile "x710-at2-mics.kicad_sch")
		(attr exclude_from_pos_files exclude_from_bom)
		(fp_circle
			(center 0 0)
			(end 0.475 0)
			(stroke
				(width 0.05)
				(type default)
			)
			(fill no)
			(layer "B.CrtYd")
		)
		(pad "1" smd circle
			(at 0 0 90)
			(size 0.75 0.75)
			(layers "B.Cu" "B.Mask")
			(net 137 "/X710-AT2 Misc/PHY_TDO")
			(pinfunction "1")
			(pintype "passive")
		)
	)
	(footprint "antmicro-footprints:C_0402_1005Metric"
		(layer "B.Cu")
		(at 81.22 103.23 90)
		(descr "Capacitor SMD 0402")
		(tags "capacitor SMD 0402")
		(property "Reference" "C184"
			(at -11.62 -0.04 90)
			(layer "B.SilkS")
			(effects
				(font
					(size 0.7 0.7)
					(thickness 0.15)
				)
				(justify right top mirror)
			)
		)
		(property "Value" "C_1u_25V_0402"
			(at -1.022927 -2.155213 90)
			(layer "B.Fab")
			(hide yes)
			(effects
				(font
					(size 0.7 0.7)
					(thickness 0.15)
				)
				(justify right top mirror)
			)
		)
		(property "Datasheet" "https://www.murata.com/products/productdetail?partno=GRM155R61E105KE11%23"
			(at 0 0 90)
			(layer "B.Fab")
			(hide yes)
			(effects
				(font
					(size 1.27 1.27)
					(thickness 0.15)
				)
				(justify mirror)
			)
		)
		(property "Description" "SMD Multilayer Ceramic Capacitor, 1 µF, 25 V, 0402 [1005 Metric], ± 10%, X5R, GRM Series"
			(at 0 0 90)
			(layer "B.Fab")
			(hide yes)
			(effects
				(font
					(size 1.27 1.27)
					(thickness 0.15)
				)
				(justify mirror)
			)
		)
		(property "MPN" "GRM155R61E105KE11J"
			(at 0 0 90)
			(unlocked yes)
			(layer "B.Fab")
			(hide yes)
			(effects
				(font
					(size 1 1)
					(thickness 0.15)
				)
				(justify mirror)
			)
		)
		(property "Manufacturer" "Murata"
			(at 0 0 90)
			(unlocked yes)
			(layer "B.Fab")
			(hide yes)
			(effects
				(font
					(size 1 1)
					(thickness 0.15)
				)
				(justify mirror)
			)
		)
		(property "License" "Apache-2.0"
			(at 0 0 90)
			(unlocked yes)
			(layer "B.Fab")
			(hide yes)
			(effects
				(font
					(size 1 1)
					(thickness 0.15)
				)
				(justify mirror)
			)
		)
		(property "Author" "Antmicro"
			(at 0 0 90)
			(unlocked yes)
			(layer "B.Fab")
			(hide yes)
			(effects
				(font
					(size 1 1)
					(thickness 0.15)
				)
				(justify mirror)
			)
		)
		(property "Val" "1u"
			(at 0 0 90)
			(unlocked yes)
			(layer "B.Fab")
			(hide yes)
			(effects
				(font
					(size 1 1)
					(thickness 0.15)
				)
				(justify mirror)
			)
		)
		(property "Voltage" "25V"
			(at 0 0 90)
			(unlocked yes)
			(layer "B.Fab")
			(hide yes)
			(effects
				(font
					(size 1 1)
					(thickness 0.15)
				)
				(justify mirror)
			)
		)
		(property "Dielectric" "X5R"
			(at 0 0 90)
			(unlocked yes)
			(layer "B.Fab")
			(hide yes)
			(effects
				(font
					(size 1 1)
					(thickness 0.15)
				)
				(justify mirror)
			)
		)
		(sheetname "/X710-AT2 power/")
		(sheetfile "x710-at2-power.kicad_sch")
		(attr smd)
		(fp_rect
			(start -0.925 0.47)
			(end 0.925 -0.47)
			(stroke
				(width 0.05)
				(type default)
			)
			(fill no)
			(layer "B.CrtYd")
		)
		(fp_line
			(start 0.504 -0.248)
			(end -0.494 -0.248)
			(stroke
				(width 0.15)
				(type solid)
			)
			(layer "B.Fab")
		)
		(fp_line
			(start -0.494 -0.248)
			(end -0.494 0.25)
			(stroke
				(width 0.15)
				(type solid)
			)
			(layer "B.Fab")
		)
		(fp_line
			(start 0.504 0.25)
			(end 0.504 -0.248)
			(stroke
				(width 0.15)
				(type solid)
			)
			(layer "B.Fab")
		)
		(fp_line
			(start -0.494 0.25)
			(end 0.504 0.25)
			(stroke
				(width 0.15)
				(type solid)
			)
			(layer "B.Fab")
		)
		(pad "1" smd roundrect
			(at -0.48 0 90)
			(size 0.59 0.64)
			(layers "B.Cu" "B.Mask" "B.Paste")
			(roundrect_rratio 0.25)
			(net 28 "GND")
			(pintype "passive")
		)
		(pad "2" smd roundrect
			(at 0.48 0 90)
			(size 0.59 0.64)
			(layers "B.Cu" "B.Mask" "B.Paste")
			(roundrect_rratio 0.25)
			(net 12 "XFI_VDD")
			(pintype "passive")
		)
	)
	(footprint "antmicro-footprints:C_0402_1005Metric"
		(layer "B.Cu")
		(at 73.75 86.75 90)
		(descr "Capacitor SMD 0402")
		(tags "capacitor SMD 0402")
		(property "Reference" "C47"
			(at -1.1 1.91 90)
			(layer "B.SilkS")
			(effects
				(font
					(size 0.7 0.7)
					(thickness 0.15)
				)
				(justify right top mirror)
			)
		)
		(property "Value" "C_100n_0402"
			(at -1.022927 -2.155213 90)
			(layer "B.Fab")
			(hide yes)
			(effects
				(font
					(size 0.7 0.7)
					(thickness 0.15)
				)
				(justify right top mirror)
			)
		)
		(property "Datasheet" "https://www.murata.com/products/productdetail?partno=GRM155R61H104KE14%23"
			(at 0 0 90)
			(layer "B.Fab")
			(hide yes)
			(effects
				(font
					(size 1.27 1.27)
					(thickness 0.15)
				)
				(justify mirror)
			)
		)
		(property "Description" "SMD Multilayer Ceramic Capacitor, 0.1 µF, 50 V, 0402 [1005 Metric], ± 10%, X5R, GRM Series"
			(at 0 0 90)
			(layer "B.Fab")
			(hide yes)
			(effects
				(font
					(size 1.27 1.27)
					(thickness 0.15)
				)
				(justify mirror)
			)
		)
		(property "MPN" "GRM155R61H104KE14D"
			(at 0 0 90)
			(unlocked yes)
			(layer "B.Fab")
			(hide yes)
			(effects
				(font
					(size 1 1)
					(thickness 0.15)
				)
				(justify mirror)
			)
		)
		(property "Val" "100n"
			(at 0 0 90)
			(unlocked yes)
			(layer "B.Fab")
			(hide yes)
			(effects
				(font
					(size 1 1)
					(thickness 0.15)
				)
				(justify mirror)
			)
		)
		(property "Voltage" "50V"
			(at 0 0 90)
			(unlocked yes)
			(layer "B.Fab")
			(hide yes)
			(effects
				(font
					(size 1 1)
					(thickness 0.15)
				)
				(justify mirror)
			)
		)
		(property "Dielectric" "X5R"
			(at 0 0 90)
			(unlocked yes)
			(layer "B.Fab")
			(hide yes)
			(effects
				(font
					(size 1 1)
					(thickness 0.15)
				)
				(justify mirror)
			)
		)
		(property "Manufacturer" "Murata"
			(at 0 0 90)
			(unlocked yes)
			(layer "B.Fab")
			(hide yes)
			(effects
				(font
					(size 1 1)
					(thickness 0.15)
				)
				(justify mirror)
			)
		)
		(property "License" "Apache-2.0"
			(at 0 0 90)
			(unlocked yes)
			(layer "B.Fab")
			(hide yes)
			(effects
				(font
					(size 1 1)
					(thickness 0.15)
				)
				(justify mirror)
			)
		)
		(property "Author" "Antmicro"
			(at 0 0 90)
			(unlocked yes)
			(layer "B.Fab")
			(hide yes)
			(effects
				(font
					(size 1 1)
					(thickness 0.15)
				)
				(justify mirror)
			)
		)
		(sheetname "/Flash memory/")
		(sheetfile "flash-memory.kicad_sch")
		(attr smd)
		(fp_rect
			(start -0.925 0.47)
			(end 0.925 -0.47)
			(stroke
				(width 0.05)
				(type default)
			)
			(fill no)
			(layer "B.CrtYd")
		)
		(fp_line
			(start 0.504 -0.248)
			(end -0.494 -0.248)
			(stroke
				(width 0.15)
				(type solid)
			)
			(layer "B.Fab")
		)
		(fp_line
			(start -0.494 -0.248)
			(end -0.494 0.25)
			(stroke
				(width 0.15)
				(type solid)
			)
			(layer "B.Fab")
		)
		(fp_line
			(start 0.504 0.25)
			(end 0.504 -0.248)
			(stroke
				(width 0.15)
				(type solid)
			)
			(layer "B.Fab")
		)
		(fp_line
			(start -0.494 0.25)
			(end 0.504 0.25)
			(stroke
				(width 0.15)
				(type solid)
			)
			(layer "B.Fab")
		)
		(pad "1" smd roundrect
			(at -0.48 0 90)
			(size 0.59 0.64)
			(layers "B.Cu" "B.Mask" "B.Paste")
			(roundrect_rratio 0.25)
			(net 28 "GND")
			(pintype "passive")
		)
		(pad "2" smd roundrect
			(at 0.48 0 90)
			(size 0.59 0.64)
			(layers "B.Cu" "B.Mask" "B.Paste")
			(roundrect_rratio 0.25)
			(net 110 "/Flash memory/+3V3_FLASH")
			(pintype "passive")
		)
	)
	(footprint "antmicro-footprints:C_0402_1005Metric"
		(layer "B.Cu")
		(at 60.670001 96.149997)
		(descr "Capacitor SMD 0402")
		(tags "capacitor SMD 0402")
		(property "Reference" "C46"
			(at -0.890001 0.560003 0)
			(layer "B.SilkS")
			(effects
				(font
					(size 0.7 0.7)
					(thickness 0.15)
				)
				(justify right top mirror)
			)
		)
		(property "Value" "C_100n_0402"
			(at -1.022927 -2.155213 0)
			(layer "B.Fab")
			(hide yes)
			(effects
				(font
					(size 0.7 0.7)
					(thickness 0.15)
				)
				(justify right top mirror)
			)
		)
		(property "Datasheet" "https://www.murata.com/products/productdetail?partno=GRM155R61H104KE14%23"
			(at 0 0 0)
			(layer "B.Fab")
			(hide yes)
			(effects
				(font
					(size 1.27 1.27)
					(thickness 0.15)
				)
				(justify mirror)
			)
		)
		(property "Description" "SMD Multilayer Ceramic Capacitor, 0.1 µF, 50 V, 0402 [1005 Metric], ± 10%, X5R, GRM Series"
			(at 0 0 0)
			(layer "B.Fab")
			(hide yes)
			(effects
				(font
					(size 1.27 1.27)
					(thickness 0.15)
				)
				(justify mirror)
			)
		)
		(property "MPN" "GRM155R61H104KE14D"
			(at 0 0 0)
			(unlocked yes)
			(layer "B.Fab")
			(hide yes)
			(effects
				(font
					(size 1 1)
					(thickness 0.15)
				)
				(justify mirror)
			)
		)
		(property "Manufacturer" "Murata"
			(at 0 0 0)
			(unlocked yes)
			(layer "B.Fab")
			(hide yes)
			(effects
				(font
					(size 1 1)
					(thickness 0.15)
				)
				(justify mirror)
			)
		)
		(property "License" "Apache-2.0"
			(at 0 0 0)
			(unlocked yes)
			(layer "B.Fab")
			(hide yes)
			(effects
				(font
					(size 1 1)
					(thickness 0.15)
				)
				(justify mirror)
			)
		)
		(property "Author" "Antmicro"
			(at 0 0 0)
			(unlocked yes)
			(layer "B.Fab")
			(hide yes)
			(effects
				(font
					(size 1 1)
					(thickness 0.15)
				)
				(justify mirror)
			)
		)
		(property "Val" "100n"
			(at 0 0 0)
			(unlocked yes)
			(layer "B.Fab")
			(hide yes)
			(effects
				(font
					(size 1 1)
					(thickness 0.15)
				)
				(justify mirror)
			)
		)
		(property "Voltage" "50V"
			(at 0 0 0)
			(unlocked yes)
			(layer "B.Fab")
			(hide yes)
			(effects
				(font
					(size 1 1)
					(thickness 0.15)
				)
				(justify mirror)
			)
		)
		(property "Dielectric" "X5R"
			(at 0 0 0)
			(unlocked yes)
			(layer "B.Fab")
			(hide yes)
			(effects
				(font
					(size 1 1)
					(thickness 0.15)
				)
				(justify mirror)
			)
		)
		(sheetname "/Power/")
		(sheetfile "power.kicad_sch")
		(attr smd)
		(fp_rect
			(start -0.925 0.47)
			(end 0.925 -0.47)
			(stroke
				(width 0.05)
				(type default)
			)
			(fill no)
			(layer "B.CrtYd")
		)
		(fp_line
			(start -0.494 -0.248)
			(end -0.494 0.25)
			(stroke
				(width 0.15)
				(type solid)
			)
			(layer "B.Fab")
		)
		(fp_line
			(start -0.494 0.25)
			(end 0.504 0.25)
			(stroke
				(width 0.15)
				(type solid)
			)
			(layer "B.Fab")
		)
		(fp_line
			(start 0.504 -0.248)
			(end -0.494 -0.248)
			(stroke
				(width 0.15)
				(type solid)
			)
			(layer "B.Fab")
		)
		(fp_line
			(start 0.504 0.25)
			(end 0.504 -0.248)
			(stroke
				(width 0.15)
				(type solid)
			)
			(layer "B.Fab")
		)
		(pad "1" smd roundrect
			(at -0.48 0)
			(size 0.59 0.64)
			(layers "B.Cu" "B.Mask" "B.Paste")
			(roundrect_rratio 0.25)
			(net 28 "GND")
			(pintype "passive")
		)
		(pad "2" smd roundrect
			(at 0.48 0)
			(size 0.59 0.64)
			(layers "B.Cu" "B.Mask" "B.Paste")
			(roundrect_rratio 0.25)
			(net 311 "/Power/+DVDD_OUT")
			(pintype "passive")
		)
	)
)
